(kicad_pcb
	(version 20260206)
	(generator "pcbnew")
	(generator_version "10.0")
	(general
		(thickness 1.6)
		(legacy_teardrops no)
	)
	(paper "A4")
	(title_block
		(title "03242023_DA0F0TMBIJ0_F0T_Motherboard_J_brd_V01_OCP.brd")
		(comment 1 "Grand Teton / footprint 37 of 6105 (J7), pads 113-224 of 291")
	)
	(layers
		(0 "F.Cu" signal "TOP")
		(4 "In1.Cu" signal "GND")
		(6 "In2.Cu" signal "IN1")
		(8 "In3.Cu" signal "GND1")
		(10 "In4.Cu" signal "IN2")
		(12 "In5.Cu" signal "GND2")
		(14 "In6.Cu" signal "IN3")
		(16 "In7.Cu" signal "GND3")
		(18 "In8.Cu" signal "VCC")
		(20 "In9.Cu" signal "VCC1")
		(22 "In10.Cu" signal "GND4")
		(24 "In11.Cu" signal "IN4")
		(26 "In12.Cu" signal "GND5")
		(28 "In13.Cu" signal "IN5")
		(30 "In14.Cu" signal "GND6")
		(32 "In15.Cu" signal "IN6")
		(34 "In16.Cu" signal "GND7")
		(2 "B.Cu" signal "BOTTOM")
		(9 "F.Adhes" user "F.Adhesive")
		(11 "B.Adhes" user "B.Adhesive")
		(13 "F.Paste" user "Package Geometry/Pastemask Top")
		(15 "B.Paste" user "Package Geometry/Pastemask Bottom")
		(5 "F.SilkS" user "Ref Des/Silkscreen Top")
		(7 "B.SilkS" user "Ref Des/Silkscreen Bottom")
		(1 "F.Mask" user "Board Geometry/Soldermask Top")
		(3 "B.Mask" user "Board Geometry/Soldermask Bottom")
		(17 "Dwgs.User" user "User.Drawings")
		(19 "Cmts.User" user "User.Comments")
		(21 "Eco1.User" user "User.Eco1")
		(23 "Eco2.User" user "User.Eco2")
		(25 "Edge.Cuts" user "Board Geometry/Outline")
		(27 "Margin" user)
		(31 "F.CrtYd" user "Package Geometry/Place Bound Top")
		(29 "B.CrtYd" user "Package Geometry/Place Bound Bottom")
		(35 "F.Fab" user "Ref Des/Assembly Top")
		(33 "B.Fab" user "Ref Des/Assembly Bottom")
	)
	(footprint ""
		(layer "F.Cu")
		(at 258.130548 -258.091686)
		(property "Reference" "J7"
			(at -3.683 -81.702148 0)
			(unlocked yes)
			(layer "F.SilkS")
			(effects
				(font
					(size 0.7874 0.5842)
					(thickness 0.1524)
				)
				(justify left)
			)
		)
		(property "Value" ""
			(at 0 0 0)
			(layer "F.Fab")
			(effects
				(font
					(size 1.27 1.27)
				)
			)
		)
		(duplicate_pad_numbers_are_jumpers no)
		(pad "113" smd rect
			(at -2.050034 36.975034 270)
			(size 0.519938 1.4986)
			(layers "F.Cu" "F.Mask" "F.Paste")
			(net "M_D_CPU0_SB_DQ<9>")
		)
		(pad "114" smd rect
			(at -2.050034 37.824918 270)
			(size 0.519938 1.4986)
			(layers "F.Cu" "F.Mask" "F.Paste")
			(net "GND")
		)
		(pad "115" smd rect
			(at -2.050034 38.675056 270)
			(size 0.519938 1.4986)
			(layers "F.Cu" "F.Mask" "F.Paste")
			(net "M_D_CPU0_SB_DQS_DP<1>")
		)
		(pad "116" smd rect
			(at -2.050034 39.52494 270)
			(size 0.519938 1.4986)
			(layers "F.Cu" "F.Mask" "F.Paste")
			(net "M_D_CPU0_SB_DQS_DN<1>")
		)
		(pad "117" smd rect
			(at -2.050034 40.375078 270)
			(size 0.519938 1.4986)
			(layers "F.Cu" "F.Mask" "F.Paste")
			(net "GND")
		)
		(pad "118" smd rect
			(at -2.050034 41.224962 270)
			(size 0.519938 1.4986)
			(layers "F.Cu" "F.Mask" "F.Paste")
			(net "M_D_CPU0_SB_DQ<12>")
		)
		(pad "119" smd rect
			(at -2.050034 42.0751 270)
			(size 0.519938 1.4986)
			(layers "F.Cu" "F.Mask" "F.Paste")
			(net "GND")
		)
		(pad "120" smd rect
			(at -2.050034 42.924984 270)
			(size 0.519938 1.4986)
			(layers "F.Cu" "F.Mask" "F.Paste")
			(net "M_D_CPU0_SB_DQ<13>")
		)
		(pad "121" smd rect
			(at -2.050034 43.775122 270)
			(size 0.519938 1.4986)
			(layers "F.Cu" "F.Mask" "F.Paste")
			(net "GND")
		)
		(pad "122" smd rect
			(at -2.050034 44.625006 270)
			(size 0.519938 1.4986)
			(layers "F.Cu" "F.Mask" "F.Paste")
			(net "M_D_CPU0_SB_DQ<16>")
		)
		(pad "123" smd rect
			(at -2.050034 45.47489 270)
			(size 0.519938 1.4986)
			(layers "F.Cu" "F.Mask" "F.Paste")
			(net "GND")
		)
		(pad "124" smd rect
			(at -2.050034 46.325028 270)
			(size 0.519938 1.4986)
			(layers "F.Cu" "F.Mask" "F.Paste")
			(net "M_D_CPU0_SB_DQ<17>")
		)
		(pad "125" smd rect
			(at -2.050034 47.174912 270)
			(size 0.519938 1.4986)
			(layers "F.Cu" "F.Mask" "F.Paste")
			(net "GND")
		)
		(pad "126" smd rect
			(at -2.050034 48.02505 270)
			(size 0.519938 1.4986)
			(layers "F.Cu" "F.Mask" "F.Paste")
			(net "M_D_CPU0_SB_DQS_DP<2>")
		)
		(pad "127" smd rect
			(at -2.050034 48.874934 270)
			(size 0.519938 1.4986)
			(layers "F.Cu" "F.Mask" "F.Paste")
			(net "M_D_CPU0_SB_DQS_DN<2>")
		)
		(pad "128" smd rect
			(at -2.050034 49.725072 270)
			(size 0.519938 1.4986)
			(layers "F.Cu" "F.Mask" "F.Paste")
			(net "GND")
		)
		(pad "129" smd rect
			(at -2.050034 50.574956 270)
			(size 0.519938 1.4986)
			(layers "F.Cu" "F.Mask" "F.Paste")
			(net "M_D_CPU0_SB_DQ<20>")
		)
		(pad "130" smd rect
			(at -2.050034 51.425094 270)
			(size 0.519938 1.4986)
			(layers "F.Cu" "F.Mask" "F.Paste")
			(net "GND")
		)
		(pad "131" smd rect
			(at -2.050034 52.274978 270)
			(size 0.519938 1.4986)
			(layers "F.Cu" "F.Mask" "F.Paste")
			(net "M_D_CPU0_SB_DQ<21>")
		)
		(pad "132" smd rect
			(at -2.050034 53.125116 270)
			(size 0.519938 1.4986)
			(layers "F.Cu" "F.Mask" "F.Paste")
			(net "GND")
		)
		(pad "133" smd rect
			(at -2.050034 53.975 270)
			(size 0.519938 1.4986)
			(layers "F.Cu" "F.Mask" "F.Paste")
			(net "M_D_CPU0_SB_DQ<24>")
		)
		(pad "134" smd rect
			(at -2.050034 54.824884 270)
			(size 0.519938 1.4986)
			(layers "F.Cu" "F.Mask" "F.Paste")
			(net "GND")
		)
		(pad "135" smd rect
			(at -2.050034 55.675022 270)
			(size 0.519938 1.4986)
			(layers "F.Cu" "F.Mask" "F.Paste")
			(net "M_D_CPU0_SB_DQ<25>")
		)
		(pad "136" smd rect
			(at -2.050034 56.524906 270)
			(size 0.519938 1.4986)
			(layers "F.Cu" "F.Mask" "F.Paste")
			(net "GND")
		)
		(pad "137" smd rect
			(at -2.050034 57.375044 270)
			(size 0.519938 1.4986)
			(layers "F.Cu" "F.Mask" "F.Paste")
			(net "M_D_CPU0_SB_DQS_DP<3>")
		)
		(pad "138" smd rect
			(at -2.050034 58.224928 270)
			(size 0.519938 1.4986)
			(layers "F.Cu" "F.Mask" "F.Paste")
			(net "M_D_CPU0_SB_DQS_DN<3>")
		)
		(pad "139" smd rect
			(at -2.050034 59.075066 270)
			(size 0.519938 1.4986)
			(layers "F.Cu" "F.Mask" "F.Paste")
			(net "GND")
		)
		(pad "140" smd rect
			(at -2.050034 59.92495 270)
			(size 0.519938 1.4986)
			(layers "F.Cu" "F.Mask" "F.Paste")
			(net "M_D_CPU0_SB_DQ<28>")
		)
		(pad "141" smd rect
			(at -2.050034 60.775088 270)
			(size 0.519938 1.4986)
			(layers "F.Cu" "F.Mask" "F.Paste")
			(net "GND")
		)
		(pad "142" smd rect
			(at -2.050034 61.624972 270)
			(size 0.519938 1.4986)
			(layers "F.Cu" "F.Mask" "F.Paste")
			(net "M_D_CPU0_SB_DQ<29>")
		)
		(pad "143" smd rect
			(at -2.050034 62.47511 270)
			(size 0.519938 1.4986)
			(layers "F.Cu" "F.Mask" "F.Paste")
			(net "GND")
		)
		(pad "144" smd rect
			(at -2.050034 63.324994 270)
			(size 0.519938 1.4986)
			(layers "F.Cu" "F.Mask" "F.Paste")
			(net "TP_CHD_CPU0_DIMM1_FRU_1")
		)
		(pad "145" smd rect
			(at 2.050034 -63.324994 270)
			(size 0.519938 1.4986)
			(layers "F.Cu" "F.Mask" "F.Paste")
			(net "P12V_S3_AUX_CPU0_NVDIMM")
		)
		(pad "146" smd rect
			(at 2.050034 -62.47511 270)
			(size 0.519938 1.4986)
			(layers "F.Cu" "F.Mask" "F.Paste")
			(net "P12V_S3_AUX_CPU0_NVDIMM")
		)
		(pad "147" smd rect
			(at 2.050034 -61.624972 270)
			(size 0.519938 1.4986)
			(layers "F.Cu" "F.Mask" "F.Paste")
			(net "PWRGD_CHD_CPU0_DIMM1")
		)
		(pad "148" smd rect
			(at 2.050034 -60.775088 270)
			(size 0.519938 1.4986)
			(layers "F.Cu" "F.Mask" "F.Paste")
			(net "PD_CHD_CPU0_DIMM1_SAA")
		)
		(pad "149" smd rect
			(at 2.050034 -59.92495 270)
			(size 0.519938 1.4986)
			(layers "F.Cu" "F.Mask" "F.Paste")
			(net "TP_CHD_CPU0_DIMM1_FRU_2")
		)
		(pad "150" smd rect
			(at 2.050034 -59.075066 270)
			(size 0.519938 1.4986)
			(layers "F.Cu" "F.Mask" "F.Paste")
			(net "TP_CHD_CPU0_DIMM1_FRU_3")
		)
		(pad "151" smd rect
			(at 2.050034 -58.224928 270)
			(size 0.519938 1.4986)
			(layers "F.Cu" "F.Mask" "F.Paste")
			(net "GND")
		)
		(pad "152" smd rect
			(at 2.050034 -57.375044 270)
			(size 0.519938 1.4986)
			(layers "F.Cu" "F.Mask" "F.Paste")
			(net "M_D_CPU0_SA_DQ<2>")
		)
		(pad "153" smd rect
			(at 2.050034 -56.524906 270)
			(size 0.519938 1.4986)
			(layers "F.Cu" "F.Mask" "F.Paste")
			(net "GND")
		)
		(pad "154" smd rect
			(at 2.050034 -55.675022 270)
			(size 0.519938 1.4986)
			(layers "F.Cu" "F.Mask" "F.Paste")
			(net "M_D_CPU0_SA_DQ<3>")
		)
		(pad "155" smd rect
			(at 2.050034 -54.824884 270)
			(size 0.519938 1.4986)
			(layers "F.Cu" "F.Mask" "F.Paste")
			(net "GND")
		)
		(pad "156" smd rect
			(at 2.050034 -53.975 270)
			(size 0.519938 1.4986)
			(layers "F.Cu" "F.Mask" "F.Paste")
			(net "M_D_CPU0_SA_DQS_DN<5>")
		)
		(pad "157" smd rect
			(at 2.050034 -53.125116 270)
			(size 0.519938 1.4986)
			(layers "F.Cu" "F.Mask" "F.Paste")
			(net "M_D_CPU0_SA_DQS_DP<5>")
		)
		(pad "158" smd rect
			(at 2.050034 -52.274978 270)
			(size 0.519938 1.4986)
			(layers "F.Cu" "F.Mask" "F.Paste")
			(net "GND")
		)
		(pad "159" smd rect
			(at 2.050034 -51.425094 270)
			(size 0.519938 1.4986)
			(layers "F.Cu" "F.Mask" "F.Paste")
			(net "M_D_CPU0_SA_DQ<6>")
		)
		(pad "160" smd rect
			(at 2.050034 -50.574956 270)
			(size 0.519938 1.4986)
			(layers "F.Cu" "F.Mask" "F.Paste")
			(net "GND")
		)
		(pad "161" smd rect
			(at 2.050034 -49.725072 270)
			(size 0.519938 1.4986)
			(layers "F.Cu" "F.Mask" "F.Paste")
			(net "M_D_CPU0_SA_DQ<7>")
		)
		(pad "162" smd rect
			(at 2.050034 -48.874934 270)
			(size 0.519938 1.4986)
			(layers "F.Cu" "F.Mask" "F.Paste")
			(net "GND")
		)
		(pad "163" smd rect
			(at 2.050034 -48.02505 270)
			(size 0.519938 1.4986)
			(layers "F.Cu" "F.Mask" "F.Paste")
			(net "M_D_CPU0_SA_DQ<10>")
		)
		(pad "164" smd rect
			(at 2.050034 -47.174912 270)
			(size 0.519938 1.4986)
			(layers "F.Cu" "F.Mask" "F.Paste")
			(net "GND")
		)
		(pad "165" smd rect
			(at 2.050034 -46.325028 270)
			(size 0.519938 1.4986)
			(layers "F.Cu" "F.Mask" "F.Paste")
			(net "M_D_CPU0_SA_DQ<11>")
		)
		(pad "166" smd rect
			(at 2.050034 -45.47489 270)
			(size 0.519938 1.4986)
			(layers "F.Cu" "F.Mask" "F.Paste")
			(net "GND")
		)
		(pad "167" smd rect
			(at 2.050034 -44.625006 270)
			(size 0.519938 1.4986)
			(layers "F.Cu" "F.Mask" "F.Paste")
			(net "M_D_CPU0_SA_DQS_DN<6>")
		)
		(pad "168" smd rect
			(at 2.050034 -43.775122 270)
			(size 0.519938 1.4986)
			(layers "F.Cu" "F.Mask" "F.Paste")
			(net "M_D_CPU0_SA_DQS_DP<6>")
		)
		(pad "169" smd rect
			(at 2.050034 -42.924984 270)
			(size 0.519938 1.4986)
			(layers "F.Cu" "F.Mask" "F.Paste")
			(net "GND")
		)
		(pad "170" smd rect
			(at 2.050034 -42.0751 270)
			(size 0.519938 1.4986)
			(layers "F.Cu" "F.Mask" "F.Paste")
			(net "M_D_CPU0_SA_DQ<14>")
		)
		(pad "171" smd rect
			(at 2.050034 -41.224962 270)
			(size 0.519938 1.4986)
			(layers "F.Cu" "F.Mask" "F.Paste")
			(net "GND")
		)
		(pad "172" smd rect
			(at 2.050034 -40.375078 270)
			(size 0.519938 1.4986)
			(layers "F.Cu" "F.Mask" "F.Paste")
			(net "M_D_CPU0_SA_DQ<15>")
		)
		(pad "173" smd rect
			(at 2.050034 -39.52494 270)
			(size 0.519938 1.4986)
			(layers "F.Cu" "F.Mask" "F.Paste")
			(net "GND")
		)
		(pad "174" smd rect
			(at 2.050034 -38.675056 270)
			(size 0.519938 1.4986)
			(layers "F.Cu" "F.Mask" "F.Paste")
			(net "M_D_CPU0_SA_DQ<18>")
		)
		(pad "175" smd rect
			(at 2.050034 -37.824918 270)
			(size 0.519938 1.4986)
			(layers "F.Cu" "F.Mask" "F.Paste")
			(net "GND")
		)
		(pad "176" smd rect
			(at 2.050034 -36.975034 270)
			(size 0.519938 1.4986)
			(layers "F.Cu" "F.Mask" "F.Paste")
			(net "M_D_CPU0_SA_DQ<19>")
		)
		(pad "177" smd rect
			(at 2.050034 -36.124896 270)
			(size 0.519938 1.4986)
			(layers "F.Cu" "F.Mask" "F.Paste")
			(net "GND")
		)
		(pad "178" smd rect
			(at 2.050034 -35.275012 270)
			(size 0.519938 1.4986)
			(layers "F.Cu" "F.Mask" "F.Paste")
			(net "M_D_CPU0_SA_DQS_DN<7>")
		)
		(pad "179" smd rect
			(at 2.050034 -34.425128 270)
			(size 0.519938 1.4986)
			(layers "F.Cu" "F.Mask" "F.Paste")
			(net "M_D_CPU0_SA_DQS_DP<7>")
		)
		(pad "180" smd rect
			(at 2.050034 -33.57499 270)
			(size 0.519938 1.4986)
			(layers "F.Cu" "F.Mask" "F.Paste")
			(net "GND")
		)
		(pad "181" smd rect
			(at 2.050034 -32.725106 270)
			(size 0.519938 1.4986)
			(layers "F.Cu" "F.Mask" "F.Paste")
			(net "M_D_CPU0_SA_DQ<22>")
		)
		(pad "182" smd rect
			(at 2.050034 -31.874968 270)
			(size 0.519938 1.4986)
			(layers "F.Cu" "F.Mask" "F.Paste")
			(net "GND")
		)
		(pad "183" smd rect
			(at 2.050034 -31.025084 270)
			(size 0.519938 1.4986)
			(layers "F.Cu" "F.Mask" "F.Paste")
			(net "M_D_CPU0_SA_DQ<23>")
		)
		(pad "184" smd rect
			(at 2.050034 -30.174946 270)
			(size 0.519938 1.4986)
			(layers "F.Cu" "F.Mask" "F.Paste")
			(net "GND")
		)
		(pad "185" smd rect
			(at 2.050034 -29.325062 270)
			(size 0.519938 1.4986)
			(layers "F.Cu" "F.Mask" "F.Paste")
			(net "M_D_CPU0_SA_DQ<26>")
		)
		(pad "186" smd rect
			(at 2.050034 -28.474924 270)
			(size 0.519938 1.4986)
			(layers "F.Cu" "F.Mask" "F.Paste")
			(net "GND")
		)
		(pad "187" smd rect
			(at 2.050034 -27.62504 270)
			(size 0.519938 1.4986)
			(layers "F.Cu" "F.Mask" "F.Paste")
			(net "M_D_CPU0_SA_DQ<27>")
		)
		(pad "188" smd rect
			(at 2.050034 -26.774902 270)
			(size 0.519938 1.4986)
			(layers "F.Cu" "F.Mask" "F.Paste")
			(net "GND")
		)
		(pad "189" smd rect
			(at 2.050034 -25.925018 270)
			(size 0.519938 1.4986)
			(layers "F.Cu" "F.Mask" "F.Paste")
			(net "M_D_CPU0_SA_DQS_DN<8>")
		)
		(pad "190" smd rect
			(at 2.050034 -25.07488 270)
			(size 0.519938 1.4986)
			(layers "F.Cu" "F.Mask" "F.Paste")
			(net "M_D_CPU0_SA_DQS_DP<8>")
		)
		(pad "191" smd rect
			(at 2.050034 -24.224996 270)
			(size 0.519938 1.4986)
			(layers "F.Cu" "F.Mask" "F.Paste")
			(net "GND")
		)
		(pad "192" smd rect
			(at 2.050034 -23.375112 270)
			(size 0.519938 1.4986)
			(layers "F.Cu" "F.Mask" "F.Paste")
			(net "M_D_CPU0_SA_DQ<30>")
		)
		(pad "193" smd rect
			(at 2.050034 -22.524974 270)
			(size 0.519938 1.4986)
			(layers "F.Cu" "F.Mask" "F.Paste")
			(net "GND")
		)
		(pad "194" smd rect
			(at 2.050034 -21.67509 270)
			(size 0.519938 1.4986)
			(layers "F.Cu" "F.Mask" "F.Paste")
			(net "M_D_CPU0_SA_DQ<31>")
		)
		(pad "195" smd rect
			(at 2.050034 -20.824952 270)
			(size 0.519938 1.4986)
			(layers "F.Cu" "F.Mask" "F.Paste")
			(net "GND")
		)
		(pad "196" smd rect
			(at 2.050034 -19.975068 270)
			(size 0.519938 1.4986)
			(layers "F.Cu" "F.Mask" "F.Paste")
			(net "M_D_CPU0_SA_CB<2>")
		)
		(pad "197" smd rect
			(at 2.050034 -19.12493 270)
			(size 0.519938 1.4986)
			(layers "F.Cu" "F.Mask" "F.Paste")
			(net "GND")
		)
		(pad "198" smd rect
			(at 2.050034 -18.275046 270)
			(size 0.519938 1.4986)
			(layers "F.Cu" "F.Mask" "F.Paste")
			(net "M_D_CPU0_SA_CB<3>")
		)
		(pad "199" smd rect
			(at 2.050034 -17.424908 270)
			(size 0.519938 1.4986)
			(layers "F.Cu" "F.Mask" "F.Paste")
			(net "GND")
		)
		(pad "200" smd rect
			(at 2.050034 -16.575024 270)
			(size 0.519938 1.4986)
			(layers "F.Cu" "F.Mask" "F.Paste")
			(net "M_D_CPU0_SA_DQS_DN<9>")
		)
		(pad "201" smd rect
			(at 2.050034 -15.724886 270)
			(size 0.519938 1.4986)
			(layers "F.Cu" "F.Mask" "F.Paste")
			(net "M_D_CPU0_SA_DQS_DP<9>")
		)
		(pad "202" smd rect
			(at 2.050034 -14.875002 270)
			(size 0.519938 1.4986)
			(layers "F.Cu" "F.Mask" "F.Paste")
			(net "GND")
		)
		(pad "203" smd rect
			(at 2.050034 -14.025118 270)
			(size 0.519938 1.4986)
			(layers "F.Cu" "F.Mask" "F.Paste")
			(net "M_D_CPU0_SA_CB<6>")
		)
		(pad "204" smd rect
			(at 2.050034 -13.17498 270)
			(size 0.519938 1.4986)
			(layers "F.Cu" "F.Mask" "F.Paste")
			(net "GND")
		)
		(pad "205" smd rect
			(at 2.050034 -12.325096 270)
			(size 0.519938 1.4986)
			(layers "F.Cu" "F.Mask" "F.Paste")
			(net "M_D_CPU0_SA_CB<7>")
		)
		(pad "206" smd rect
			(at 2.050034 -11.474958 270)
			(size 0.519938 1.4986)
			(layers "F.Cu" "F.Mask" "F.Paste")
			(net "GND")
		)
		(pad "207" smd rect
			(at 2.050034 -10.625074 270)
			(size 0.519938 1.4986)
			(layers "F.Cu" "F.Mask" "F.Paste")
			(net "RST_M_CD_CPU0_FPGA_N")
		)
		(pad "208" smd rect
			(at 2.050034 -9.774936 270)
			(size 0.519938 1.4986)
			(layers "F.Cu" "F.Mask" "F.Paste")
			(net "GND")
		)
		(pad "209" smd rect
			(at 2.050034 -8.925052 270)
			(size 0.519938 1.4986)
			(layers "F.Cu" "F.Mask" "F.Paste")
			(net "M_D_CPU0_SA_CS_N<1>")
		)
		(pad "210" smd rect
			(at 2.050034 -8.074914 270)
			(size 0.519938 1.4986)
			(layers "F.Cu" "F.Mask" "F.Paste")
			(net "GND")
		)
		(pad "211" smd rect
			(at 2.050034 -7.22503 270)
			(size 0.519938 1.4986)
			(layers "F.Cu" "F.Mask" "F.Paste")
			(net "M_D_CPU0_SA_CA<1>")
		)
		(pad "212" smd rect
			(at 2.050034 -6.374892 270)
			(size 0.519938 1.4986)
			(layers "F.Cu" "F.Mask" "F.Paste")
			(net "GND")
		)
		(pad "213" smd rect
			(at 2.050034 -5.525008 270)
			(size 0.519938 1.4986)
			(layers "F.Cu" "F.Mask" "F.Paste")
			(net "M_D_CPU0_SA_CA<3>")
		)
		(pad "214" smd rect
			(at 2.050034 -4.675124 270)
			(size 0.519938 1.4986)
			(layers "F.Cu" "F.Mask" "F.Paste")
			(net "GND")
		)
		(pad "215" smd rect
			(at 2.050034 -3.824986 270)
			(size 0.519938 1.4986)
			(layers "F.Cu" "F.Mask" "F.Paste")
			(net "M_D_CPU0_SA_CA<5>")
		)
		(pad "216" smd rect
			(at 2.050034 -2.975102 270)
			(size 0.519938 1.4986)
			(layers "F.Cu" "F.Mask" "F.Paste")
			(net "GND")
		)
		(pad "217" smd rect
			(at 2.050034 -2.124964 270)
			(size 0.519938 1.4986)
			(layers "F.Cu" "F.Mask" "F.Paste")
			(net "M_D_CPU0_CLK_DP<0>")
		)
		(pad "218" smd rect
			(at 2.050034 -1.27508 270)
			(size 0.519938 1.4986)
			(layers "F.Cu" "F.Mask" "F.Paste")
			(net "M_D_CPU0_CLK_DN<0>")
		)
		(pad "219" smd rect
			(at 2.050034 -0.424942 270)
			(size 0.519938 1.4986)
			(layers "F.Cu" "F.Mask" "F.Paste")
			(net "GND")
		)
		(pad "220" smd rect
			(at 2.050034 5.525008 270)
			(size 0.519938 1.4986)
			(layers "F.Cu" "F.Mask" "F.Paste")
			(net "TP_CHD_CPU0_DIMM1_FRU_4")
		)
		(pad "221" smd rect
			(at 2.050034 6.374892 270)
			(size 0.519938 1.4986)
			(layers "F.Cu" "F.Mask" "F.Paste")
			(net "M_D_CPU0_SB_CA<1>")
		)
		(pad "222" smd rect
			(at 2.050034 7.22503 270)
			(size 0.519938 1.4986)
			(layers "F.Cu" "F.Mask" "F.Paste")
			(net "GND")
		)
		(pad "223" smd rect
			(at 2.050034 8.074914 270)
			(size 0.519938 1.4986)
			(layers "F.Cu" "F.Mask" "F.Paste")
			(net "M_D_CPU0_SB_CA<3>")
		)
		(pad "224" smd rect
			(at 2.050034 8.925052 270)
			(size 0.519938 1.4986)
			(layers "F.Cu" "F.Mask" "F.Paste")
			(net "GND")
		)
	)
)
